(kicad_pcb
	(version 20260206)
	(generator "pcbnew")
	(generator_version "10.0")
	(general
		(thickness 1.6)
		(legacy_teardrops no)
	)
	(paper "A4")
	(title_block
		(title "04192023_DAF0TMB3IC0_F0TG_MB_C_brd_V02_OCP.brd")
		(comment 1 "Grand Teton / footprints 8268-8275 of 8354")
	)
	(layers
		(0 "F.Cu" signal "TOP")
		(4 "In1.Cu" signal "GND")
		(6 "In2.Cu" signal "IN1")
		(8 "In3.Cu" signal "GND1")
		(10 "In4.Cu" signal "IN2")
		(12 "In5.Cu" signal "GND2")
		(14 "In6.Cu" signal "IN3")
		(16 "In7.Cu" signal "GND3")
		(18 "In8.Cu" signal "VCC")
		(20 "In9.Cu" signal "VCC1")
		(22 "In10.Cu" signal "GND4")
		(24 "In11.Cu" signal "IN4")
		(26 "In12.Cu" signal "GND5")
		(28 "In13.Cu" signal "IN5")
		(30 "In14.Cu" signal "GND6")
		(32 "In15.Cu" signal "IN6")
		(34 "In16.Cu" signal "GND7")
		(2 "B.Cu" signal "BOTTOM")
		(9 "F.Adhes" user "F.Adhesive")
		(11 "B.Adhes" user "B.Adhesive")
		(13 "F.Paste" user "Package Geometry/Pastemask Top")
		(15 "B.Paste" user "Package Geometry/Pastemask Bottom")
		(5 "F.SilkS" user "Ref Des/Silkscreen Top")
		(7 "B.SilkS" user "Ref Des/Silkscreen Bottom")
		(1 "F.Mask" user "Board Geometry/Soldermask Top")
		(3 "B.Mask" user "Board Geometry/Soldermask Bottom")
		(17 "Dwgs.User" user "User.Drawings")
		(19 "Cmts.User" user "User.Comments")
		(21 "Eco1.User" user "User.Eco1")
		(23 "Eco2.User" user "User.Eco2")
		(25 "Edge.Cuts" user "Board Geometry/Outline")
		(27 "Margin" user)
		(31 "F.CrtYd" user "Package Geometry/Place Bound Top")
		(29 "B.CrtYd" user "Package Geometry/Place Bound Bottom")
		(35 "F.Fab" user "Ref Des/Assembly Top")
		(33 "B.Fab" user "Ref Des/Assembly Bottom")
	)
	(footprint ""
		(layer "B.Cu")
		(at 388.537958 -203.577952 180)
		(property "Reference" "R30"
			(at 0 0 0)
			(layer "B.SilkS")
			(hide yes)
			(effects
				(font
					(size 1.27 1.27)
				)
				(justify mirror)
			)
		)
		(property "Value" ""
			(at 0 0 0)
			(layer "B.Fab")
			(effects
				(font
					(size 1.27 1.27)
				)
				(justify mirror)
			)
		)
		(duplicate_pad_numbers_are_jumpers no)
		(fp_line
			(start 0.7874 0.4064)
			(end 0.7874 -0.4064)
			(stroke
				(width 0.1524)
				(type default)
			)
			(layer "B.SilkS")
		)
		(fp_line
			(start 0.7874 -0.4064)
			(end -0.7874 -0.4064)
			(stroke
				(width 0.1524)
				(type default)
			)
			(layer "B.SilkS")
		)
		(fp_line
			(start -0.7874 0.4064)
			(end 0.7874 0.4064)
			(stroke
				(width 0.1524)
				(type default)
			)
			(layer "B.SilkS")
		)
		(fp_line
			(start -0.7874 -0.4064)
			(end -0.7874 0.4064)
			(stroke
				(width 0.1524)
				(type default)
			)
			(layer "B.SilkS")
		)
		(fp_line
			(start 0.67945 0.3048)
			(end 0.67945 -0.305054)
			(stroke
				(width 0.1)
				(type default)
			)
			(layer "B.Fab")
		)
		(fp_line
			(start 0.67945 -0.305054)
			(end 0.12065 -0.305054)
			(stroke
				(width 0.1)
				(type default)
			)
			(layer "B.Fab")
		)
		(fp_line
			(start 0.12065 0.3048)
			(end 0.67945 0.3048)
			(stroke
				(width 0.1)
				(type default)
			)
			(layer "B.Fab")
		)
		(fp_line
			(start 0.12065 0.2794)
			(end 0.12065 0.3048)
			(stroke
				(width 0.1)
				(type default)
			)
			(layer "B.Fab")
		)
		(fp_line
			(start 0.12065 -0.2794)
			(end -0.12065 -0.2794)
			(stroke
				(width 0.1)
				(type default)
			)
			(layer "B.Fab")
		)
		(fp_line
			(start 0.12065 -0.305054)
			(end 0.12065 -0.2794)
			(stroke
				(width 0.1)
				(type default)
			)
			(layer "B.Fab")
		)
		(fp_line
			(start -0.120396 0.3048)
			(end -0.120396 0.2794)
			(stroke
				(width 0.1)
				(type default)
			)
			(layer "B.Fab")
		)
		(fp_line
			(start -0.120396 0.2794)
			(end 0.12065 0.2794)
			(stroke
				(width 0.1)
				(type default)
			)
			(layer "B.Fab")
		)
		(fp_line
			(start -0.12065 -0.2794)
			(end -0.12065 -0.3048)
			(stroke
				(width 0.1)
				(type default)
			)
			(layer "B.Fab")
		)
		(fp_line
			(start -0.12065 -0.3048)
			(end -0.67945 -0.3048)
			(stroke
				(width 0.1)
				(type default)
			)
			(layer "B.Fab")
		)
		(fp_line
			(start -0.67945 0.3048)
			(end -0.120396 0.3048)
			(stroke
				(width 0.1)
				(type default)
			)
			(layer "B.Fab")
		)
		(fp_line
			(start -0.67945 -0.3048)
			(end -0.67945 0.3048)
			(stroke
				(width 0.1)
				(type default)
			)
			(layer "B.Fab")
		)
		(pad "1" smd circle
			(at 0.40005 0)
			(size 0 0)
			(layers "B.Cu" "B.Mask" "B.Paste")
			(net "SMB_CPU0_3_R_SDA")
		)
		(pad "2" smd circle
			(at -0.40005 0)
			(size 0 0)
			(layers "B.Cu" "B.Mask" "B.Paste")
			(net "SMB_CPU0_3_SDA")
		)
	)
	(footprint ""
		(layer "B.Cu")
		(at 474.16466 -117.700806)
		(property "Reference" "DB5"
			(at 2.584704 -5.768848 270)
			(unlocked yes)
			(layer "B.SilkS")
			(effects
				(font
					(size 0.7874 0.5842)
					(thickness 0.1524)
				)
				(justify left mirror)
			)
		)
		(property "Value" ""
			(at 0 0 0)
			(layer "B.Fab")
			(effects
				(font
					(size 1.27 1.27)
				)
				(justify mirror)
			)
		)
		(duplicate_pad_numbers_are_jumpers no)
		(fp_line
			(start -3.330702 -4.771136)
			(end 0 4.011168)
			(stroke
				(width 0.1524)
				(type default)
			)
			(layer "B.SilkS")
		)
		(fp_line
			(start 0 4.011168)
			(end 2.826766 -3.442462)
			(stroke
				(width 0.1524)
				(type default)
			)
			(layer "B.SilkS")
		)
		(fp_line
			(start 3.18389 -4.383786)
			(end 3.330702 -4.771136)
			(stroke
				(width 0.1524)
				(type default)
			)
			(layer "B.SilkS")
		)
		(fp_line
			(start 3.330702 -4.771136)
			(end -3.330702 -4.771136)
			(stroke
				(width 0.1524)
				(type default)
			)
			(layer "B.SilkS")
		)
		(fp_line
			(start -3.330702 -4.771136)
			(end 0 4.011168)
			(stroke
				(width 0.1)
				(type default)
			)
			(layer "B.Fab")
		)
		(fp_line
			(start 0 4.011168)
			(end 3.330702 -4.771136)
			(stroke
				(width 0.1)
				(type default)
			)
			(layer "B.Fab")
		)
		(fp_line
			(start 3.330702 -4.771136)
			(end -3.330702 -4.771136)
			(stroke
				(width 0.1)
				(type default)
			)
			(layer "B.Fab")
		)
		(pad "1" thru_hole circle
			(at 0 0 180)
			(size 2.159 2.159)
			(drill 1.7018)
			(layers "*.Cu" "*.Mask")
			(remove_unused_layers no)
			(net "T1_GND")
			(clearance 0.0254)
			(thermal_gap 0.0254)
		)
		(pad "2" thru_hole circle
			(at 1.27 -3.348736 180)
			(size 2.159 2.159)
			(drill 1.7018)
			(layers "*.Cu" "*.Mask")
			(remove_unused_layers no)
			(net "TDR_SE_45_OHM_IN4")
			(clearance 0.0254)
			(thermal_gap 0.0254)
		)
		(pad "3" thru_hole circle
			(at -1.27 -3.348736 180)
			(size 2.159 2.159)
			(drill 1.7018)
			(layers "*.Cu" "*.Mask")
			(remove_unused_layers no)
			(net "TDR_SE_45_OHM_IN4")
			(clearance 0.0254)
			(thermal_gap 0.0254)
		)
	)
	(footprint ""
		(layer "B.Cu")
		(at 13.65885 -402.839174 180)
		(property "Reference" "R6859"
			(at 0 0 0)
			(layer "B.SilkS")
			(hide yes)
			(effects
				(font
					(size 1.27 1.27)
				)
				(justify mirror)
			)
		)
		(property "Value" ""
			(at 0 0 0)
			(layer "B.Fab")
			(effects
				(font
					(size 1.27 1.27)
				)
				(justify mirror)
			)
		)
		(duplicate_pad_numbers_are_jumpers no)
		(fp_line
			(start 0.7874 0.4064)
			(end 0.7874 -0.4064)
			(stroke
				(width 0.1524)
				(type default)
			)
			(layer "B.SilkS")
		)
		(fp_line
			(start 0.7874 -0.4064)
			(end -0.7874 -0.4064)
			(stroke
				(width 0.1524)
				(type default)
			)
			(layer "B.SilkS")
		)
		(fp_line
			(start -0.7874 0.4064)
			(end 0.7874 0.4064)
			(stroke
				(width 0.1524)
				(type default)
			)
			(layer "B.SilkS")
		)
		(fp_line
			(start -0.7874 -0.4064)
			(end -0.7874 0.4064)
			(stroke
				(width 0.1524)
				(type default)
			)
			(layer "B.SilkS")
		)
		(fp_line
			(start 0.67945 0.3048)
			(end 0.67945 -0.305054)
			(stroke
				(width 0.1)
				(type default)
			)
			(layer "B.Fab")
		)
		(fp_line
			(start 0.67945 -0.305054)
			(end 0.12065 -0.305054)
			(stroke
				(width 0.1)
				(type default)
			)
			(layer "B.Fab")
		)
		(fp_line
			(start 0.12065 0.3048)
			(end 0.67945 0.3048)
			(stroke
				(width 0.1)
				(type default)
			)
			(layer "B.Fab")
		)
		(fp_line
			(start 0.12065 0.2794)
			(end 0.12065 0.3048)
			(stroke
				(width 0.1)
				(type default)
			)
			(layer "B.Fab")
		)
		(fp_line
			(start 0.12065 -0.2794)
			(end -0.12065 -0.2794)
			(stroke
				(width 0.1)
				(type default)
			)
			(layer "B.Fab")
		)
		(fp_line
			(start 0.12065 -0.305054)
			(end 0.12065 -0.2794)
			(stroke
				(width 0.1)
				(type default)
			)
			(layer "B.Fab")
		)
		(fp_line
			(start -0.120396 0.3048)
			(end -0.120396 0.2794)
			(stroke
				(width 0.1)
				(type default)
			)
			(layer "B.Fab")
		)
		(fp_line
			(start -0.120396 0.2794)
			(end 0.12065 0.2794)
			(stroke
				(width 0.1)
				(type default)
			)
			(layer "B.Fab")
		)
		(fp_line
			(start -0.12065 -0.2794)
			(end -0.12065 -0.3048)
			(stroke
				(width 0.1)
				(type default)
			)
			(layer "B.Fab")
		)
		(fp_line
			(start -0.12065 -0.3048)
			(end -0.67945 -0.3048)
			(stroke
				(width 0.1)
				(type default)
			)
			(layer "B.Fab")
		)
		(fp_line
			(start -0.67945 0.3048)
			(end -0.120396 0.3048)
			(stroke
				(width 0.1)
				(type default)
			)
			(layer "B.Fab")
		)
		(fp_line
			(start -0.67945 -0.3048)
			(end -0.67945 0.3048)
			(stroke
				(width 0.1)
				(type default)
			)
			(layer "B.Fab")
		)
		(pad "1" smd circle
			(at 0.40005 0)
			(size 0 0)
			(layers "B.Cu" "B.Mask" "B.Paste")
			(net "SMB_VR_3V3STBY_SDA")
		)
		(pad "2" smd circle
			(at -0.40005 0)
			(size 0 0)
			(layers "B.Cu" "B.Mask" "B.Paste")
			(net "P0V9_RETIMER_CPU1_PMSDA")
		)
	)
	(footprint ""
		(layer "B.Cu")
		(at 309.277766 -416.899344 90)
		(property "Reference" "C6535"
			(at 0 0 90)
			(layer "B.SilkS")
			(hide yes)
			(effects
				(font
					(size 1.27 1.27)
				)
				(justify mirror)
			)
		)
		(property "Value" ""
			(at 0 0 90)
			(layer "B.Fab")
			(effects
				(font
					(size 1.27 1.27)
				)
				(justify mirror)
			)
		)
		(duplicate_pad_numbers_are_jumpers no)
		(fp_line
			(start 0.299974 -0.150114)
			(end -0.299974 -0.150114)
			(stroke
				(width 0.1)
				(type default)
			)
			(layer "B.Fab")
		)
		(fp_line
			(start -0.299974 -0.150114)
			(end -0.299974 0.150114)
			(stroke
				(width 0.1)
				(type default)
			)
			(layer "B.Fab")
		)
		(fp_line
			(start 0.299974 0.150114)
			(end 0.299974 -0.150114)
			(stroke
				(width 0.1)
				(type default)
			)
			(layer "B.Fab")
		)
		(fp_line
			(start -0.299974 0.150114)
			(end 0.299974 0.150114)
			(stroke
				(width 0.1)
				(type default)
			)
			(layer "B.Fab")
		)
		(pad "1" smd rect
			(at 0.2667 0 270)
			(size 0.3048 0.381)
			(layers "B.Cu" "B.Mask" "B.Paste")
			(net "P5E_CPU0_P1_TX_BUF_C_DP<1>")
		)
		(pad "2" smd rect
			(at -0.2667 0 270)
			(size 0.3048 0.381)
			(layers "B.Cu" "B.Mask" "B.Paste")
			(net "P5E_CPU0_P1_TX_BUF_DP<1>")
		)
	)
	(footprint ""
		(layer "B.Cu")
		(at 107.200192 -29.55544 -90)
		(property "Reference" "C6102"
			(at 0 0 90)
			(layer "B.SilkS")
			(hide yes)
			(effects
				(font
					(size 1.27 1.27)
				)
				(justify mirror)
			)
		)
		(property "Value" ""
			(at 0 0 90)
			(layer "B.Fab")
			(effects
				(font
					(size 1.27 1.27)
				)
				(justify mirror)
			)
		)
		(duplicate_pad_numbers_are_jumpers no)
		(fp_line
			(start -0.7874 0.4064)
			(end 0.7874 0.4064)
			(stroke
				(width 0.1524)
				(type default)
			)
			(layer "B.SilkS")
		)
		(fp_line
			(start 0.7874 0.4064)
			(end 0.7874 -0.4064)
			(stroke
				(width 0.1524)
				(type default)
			)
			(layer "B.SilkS")
		)
		(fp_line
			(start -0.7874 -0.4064)
			(end -0.7874 0.4064)
			(stroke
				(width 0.1524)
				(type default)
			)
			(layer "B.SilkS")
		)
		(fp_line
			(start 0.7874 -0.4064)
			(end -0.7874 -0.4064)
			(stroke
				(width 0.1524)
				(type default)
			)
			(layer "B.SilkS")
		)
		(fp_line
			(start -0.67945 0.3048)
			(end -0.120396 0.3048)
			(stroke
				(width 0.1)
				(type default)
			)
			(layer "B.Fab")
		)
		(fp_line
			(start -0.120396 0.3048)
			(end -0.120396 0.2794)
			(stroke
				(width 0.1)
				(type default)
			)
			(layer "B.Fab")
		)
		(fp_line
			(start 0.12065 0.3048)
			(end 0.67945 0.3048)
			(stroke
				(width 0.1)
				(type default)
			)
			(layer "B.Fab")
		)
		(fp_line
			(start 0.67945 0.3048)
			(end 0.67945 -0.305054)
			(stroke
				(width 0.1)
				(type default)
			)
			(layer "B.Fab")
		)
		(fp_line
			(start -0.120396 0.2794)
			(end 0.12065 0.2794)
			(stroke
				(width 0.1)
				(type default)
			)
			(layer "B.Fab")
		)
		(fp_line
			(start 0.12065 0.2794)
			(end 0.12065 0.3048)
			(stroke
				(width 0.1)
				(type default)
			)
			(layer "B.Fab")
		)
		(fp_line
			(start -0.12065 -0.2794)
			(end -0.12065 -0.3048)
			(stroke
				(width 0.1)
				(type default)
			)
			(layer "B.Fab")
		)
		(fp_line
			(start 0.12065 -0.2794)
			(end -0.12065 -0.2794)
			(stroke
				(width 0.1)
				(type default)
			)
			(layer "B.Fab")
		)
		(fp_line
			(start -0.67945 -0.3048)
			(end -0.67945 0.3048)
			(stroke
				(width 0.1)
				(type default)
			)
			(layer "B.Fab")
		)
		(fp_line
			(start -0.12065 -0.3048)
			(end -0.67945 -0.3048)
			(stroke
				(width 0.1)
				(type default)
			)
			(layer "B.Fab")
		)
		(fp_line
			(start 0.12065 -0.305054)
			(end 0.12065 -0.2794)
			(stroke
				(width 0.1)
				(type default)
			)
			(layer "B.Fab")
		)
		(fp_line
			(start 0.67945 -0.305054)
			(end 0.12065 -0.305054)
			(stroke
				(width 0.1)
				(type default)
			)
			(layer "B.Fab")
		)
		(pad "1" smd circle
			(at 0.40005 0 90)
			(size 0 0)
			(layers "B.Cu" "B.Mask" "B.Paste")
			(net "P3V3_AUX_CPU0_USB2_AVDD33")
		)
		(pad "2" smd circle
			(at -0.40005 0 90)
			(size 0 0)
			(layers "B.Cu" "B.Mask" "B.Paste")
			(net "GND")
		)
	)
	(footprint ""
		(layer "B.Cu")
		(at 343.514934 -301.911258 -90)
		(property "Reference" "R4303"
			(at 0 0 90)
			(layer "B.SilkS")
			(hide yes)
			(effects
				(font
					(size 1.27 1.27)
				)
				(justify mirror)
			)
		)
		(property "Value" ""
			(at 0 0 90)
			(layer "B.Fab")
			(effects
				(font
					(size 1.27 1.27)
				)
				(justify mirror)
			)
		)
		(duplicate_pad_numbers_are_jumpers no)
		(fp_line
			(start -0.374142 0.4064)
			(end 0.311658 0.4064)
			(stroke
				(width 0.1524)
				(type default)
			)
			(layer "B.SilkS")
		)
		(fp_line
			(start 0.7874 0.005334)
			(end 0.7874 -0.4064)
			(stroke
				(width 0.1524)
				(type default)
			)
			(layer "B.SilkS")
		)
		(fp_line
			(start -0.7874 -0.4064)
			(end -0.7874 0.005334)
			(stroke
				(width 0.1524)
				(type default)
			)
			(layer "B.SilkS")
		)
		(fp_line
			(start 0.7874 -0.4064)
			(end -0.7874 -0.4064)
			(stroke
				(width 0.1524)
				(type default)
			)
			(layer "B.SilkS")
		)
		(fp_line
			(start -0.67945 0.3048)
			(end -0.120396 0.3048)
			(stroke
				(width 0.1)
				(type default)
			)
			(layer "B.Fab")
		)
		(fp_line
			(start -0.120396 0.3048)
			(end -0.120396 0.2794)
			(stroke
				(width 0.1)
				(type default)
			)
			(layer "B.Fab")
		)
		(fp_line
			(start 0.12065 0.3048)
			(end 0.67945 0.3048)
			(stroke
				(width 0.1)
				(type default)
			)
			(layer "B.Fab")
		)
		(fp_line
			(start 0.67945 0.3048)
			(end 0.67945 -0.305054)
			(stroke
				(width 0.1)
				(type default)
			)
			(layer "B.Fab")
		)
		(fp_line
			(start -0.120396 0.2794)
			(end 0.12065 0.2794)
			(stroke
				(width 0.1)
				(type default)
			)
			(layer "B.Fab")
		)
		(fp_line
			(start 0.12065 0.2794)
			(end 0.12065 0.3048)
			(stroke
				(width 0.1)
				(type default)
			)
			(layer "B.Fab")
		)
		(fp_line
			(start -0.12065 -0.2794)
			(end -0.12065 -0.3048)
			(stroke
				(width 0.1)
				(type default)
			)
			(layer "B.Fab")
		)
		(fp_line
			(start 0.12065 -0.2794)
			(end -0.12065 -0.2794)
			(stroke
				(width 0.1)
				(type default)
			)
			(layer "B.Fab")
		)
		(fp_line
			(start -0.67945 -0.3048)
			(end -0.67945 0.3048)
			(stroke
				(width 0.1)
				(type default)
			)
			(layer "B.Fab")
		)
		(fp_line
			(start -0.12065 -0.3048)
			(end -0.67945 -0.3048)
			(stroke
				(width 0.1)
				(type default)
			)
			(layer "B.Fab")
		)
		(fp_line
			(start 0.12065 -0.305054)
			(end 0.12065 -0.2794)
			(stroke
				(width 0.1)
				(type default)
			)
			(layer "B.Fab")
		)
		(fp_line
			(start 0.67945 -0.305054)
			(end 0.12065 -0.305054)
			(stroke
				(width 0.1)
				(type default)
			)
			(layer "B.Fab")
		)
		(pad "1" smd circle
			(at 0.40005 0 90)
			(size 0 0)
			(layers "B.Cu" "B.Mask" "B.Paste")
			(net "CLK_100M_CPU0_CLK12_R_DP")
		)
		(pad "2" smd circle
			(at -0.40005 0 90)
			(size 0 0)
			(layers "B.Cu" "B.Mask" "B.Paste")
			(net "CLK_100M_CPU0_CLK12_DP")
		)
	)
	(footprint ""
		(layer "B.Cu")
		(at 396.696184 -385.529328)
		(property "Reference" "ME8"
			(at 0 0 0)
			(layer "B.SilkS")
			(hide yes)
			(effects
				(font
					(size 1.27 1.27)
				)
				(justify mirror)
			)
		)
		(property "Value" ""
			(at 0 0 0)
			(layer "B.Fab")
			(effects
				(font
					(size 1.27 1.27)
				)
				(justify mirror)
			)
		)
		(duplicate_pad_numbers_are_jumpers no)
		(zone
			(layer "B.Cu")
			(hatch none 0.5)
			(connect_pads
				(clearance 0)
			)
			(min_thickness 0.25)
			(keepout
				(tracks allowed)
				(vias allowed)
				(pads allowed)
				(copperpour allowed)
				(footprints not_allowed)
			)
			(placement
				(enabled no)
				(sheetname "")
			)
			(fill
				(thermal_gap 0.5)
				(thermal_bridge_width 0.5)
				(island_removal_mode 0)
			)
			(polygon
				(pts
					(arc
						(start 464.0199 -364.816136)
						(mid 444.01994 -364.816136)
						(end 464.0199 -364.816136)
					)
				)
			)
		)
	)
	(footprint ""
		(layer "B.Cu")
		(at 336.180684 -335.041494 90)
		(property "Reference" "PC89_1"
			(at 0 0 90)
			(layer "B.SilkS")
			(hide yes)
			(effects
				(font
					(size 1.27 1.27)
				)
				(justify mirror)
			)
		)
		(property "Value" ""
			(at 0 0 90)
			(layer "B.Fab")
			(effects
				(font
					(size 1.27 1.27)
				)
				(justify mirror)
			)
		)
		(duplicate_pad_numbers_are_jumpers no)
		(fp_line
			(start 1.524 -0.762)
			(end -1.524 -0.762)
			(stroke
				(width 0.1524)
				(type default)
			)
			(layer "B.SilkS")
		)
		(fp_line
			(start -1.524 -0.762)
			(end -1.524 0.762)
			(stroke
				(width 0.1524)
				(type default)
			)
			(layer "B.SilkS")
		)
		(fp_line
			(start 1.524 0.762)
			(end 1.524 -0.762)
			(stroke
				(width 0.1524)
				(type default)
			)
			(layer "B.SilkS")
		)
		(fp_line
			(start -1.524 0.762)
			(end 1.524 0.762)
			(stroke
				(width 0.1524)
				(type default)
			)
			(layer "B.SilkS")
		)
		(fp_line
			(start 1.1049 -0.724916)
			(end 1.1049 0.724916)
			(stroke
				(width 0.1)
				(type default)
			)
			(layer "B.Fab")
		)
		(fp_line
			(start -1.1049 -0.724916)
			(end 1.1049 -0.724916)
			(stroke
				(width 0.1)
				(type default)
			)
			(layer "B.Fab")
		)
		(fp_line
			(start 1.1049 0.724916)
			(end -1.1049 0.724916)
			(stroke
				(width 0.1)
				(type default)
			)
			(layer "B.Fab")
		)
		(fp_line
			(start -1.1049 0.724916)
			(end -1.1049 -0.724916)
			(stroke
				(width 0.1)
				(type default)
			)
			(layer "B.Fab")
		)
		(pad "1" smd rect
			(at 0.889 0 90)
			(size 1.016 1.27)
			(layers "B.Cu" "B.Mask" "B.Paste")
			(net "SW_P12V_AUX_PVDDCR_CPU1_P0_FLT")
		)
		(pad "2" smd rect
			(at -0.889 0 90)
			(size 1.016 1.27)
			(layers "B.Cu" "B.Mask" "B.Paste")
			(net "GND")
		)
	)
)
